# TIMECARD (Time Appliance Project (Time Card)) — schematic netlist excerpt (pin names and nets, part order shuffled) for the footprints in the layout excerpt that follows; sources: Cadence DE-HDL packaged netlist, KiCad conversion of R4006-B0001-02_R01.brd

TP16  TP_PIONT  pkg TP010CT020B030_PTH  page 25 : \1\ = R_BNO080_RST_N
SP39  SOLDER_PREFORM  pkg 0201_SOLDER_PREFORM_4MIL  page 34 : \1\ = NC ; \2\ = NC
R449  RESISTOR  33OHM 1%  pkg SMC_0402R_H016  page 24 : \1\ = MUX1_SEL ; \2\ = FT4232_MUX1_SEL

(kicad_pcb
	(version 20260206)
	(generator "pcbnew")
	(generator_version "10.0")
	(general
		(thickness 1.6)
		(legacy_teardrops no)
	)
	(paper "A4")
	(title_block
		(title "timecard-production-celestica-r4006 — R4006-B0001-02_R01.brd")
		(comment 1 "Time Appliance Project (Time Card) / footprints 314-316 of 1113")
	)
	(layers
		(0 "F.Cu" signal "TOP")
		(4 "In1.Cu" signal "L02_GND1")
		(6 "In2.Cu" signal "L03_SIG1")
		(8 "In3.Cu" signal "L04_GND2")
		(10 "In4.Cu" signal "L05_VCC1")
		(12 "In5.Cu" signal "L06_VCC2")
		(14 "In6.Cu" signal "L07_GND3")
		(16 "In7.Cu" signal "L08_SIG2")
		(18 "In8.Cu" signal "L09_GND4")
		(2 "B.Cu" signal "BOTTOM")
		(9 "F.Adhes" user "F.Adhesive")
		(11 "B.Adhes" user "B.Adhesive")
		(13 "F.Paste" user "Package Geometry/Pastemask Top")
		(15 "B.Paste" user "Package Geometry/Pastemask Bottom")
		(5 "F.SilkS" user "Ref Des/Silkscreen Top")
		(7 "B.SilkS" user "Ref Des/Silkscreen Bottom")
		(1 "F.Mask" user "Board Geometry/Soldermask Top")
		(3 "B.Mask" user "Board Geometry/Soldermask Bottom")
		(17 "Dwgs.User" user "User.Drawings")
		(19 "Cmts.User" user "User.Comments")
		(21 "Eco1.User" user "User.Eco1")
		(23 "Eco2.User" user "User.Eco2")
		(25 "Edge.Cuts" user "Board Geometry/Outline")
		(27 "Margin" user)
		(31 "F.CrtYd" user "Package Geometry/Place Bound Top")
		(29 "B.CrtYd" user "Package Geometry/Place Bound Bottom")
		(35 "F.Fab" user "Ref Des/Assembly Top")
		(33 "B.Fab" user "Ref Des/Assembly Bottom")
	)
	(footprint ""
		(layer "F.Cu")
		(at 98.044 -95.4532 180)
		(property "Reference" "R449"
			(at 1.143 3.05943 0)
			(unlocked yes)
			(layer "F.SilkS")
			(effects
				(font
					(size 0.7874 0.5842)
					(thickness 0.1524)
				)
			)
		)
		(property "Value" "VAL*"
			(at 0.02032 2.13233 180)
			(unlocked yes)
			(layer "F.Fab")
			(hide yes)
			(effects
				(font
					(size 0.7874 0.5842)
					(thickness 0.1524)
				)
			)
		)
		(property "Tolerance" "TOL*"
			(at 0.044704 3.05435 180)
			(unlocked yes)
			(layer "Cmts.User")
			(hide yes)
			(effects
				(font
					(size 0.7874 0.5842)
					(thickness 0.1524)
				)
			)
		)
		(property "User Part Number" "PARTNUM*"
			(at 0.02032 4.024884 180)
			(unlocked yes)
			(layer "Cmts.User")
			(hide yes)
			(effects
				(font
					(size 0.7874 0.5842)
					(thickness 0.1524)
				)
			)
		)
		(property "Device Type" "RESISTOR-G155-133R0-01,33OHM,1%"
			(at 0.008382 1.210564 180)
			(unlocked yes)
			(layer "F.Fab")
			(hide yes)
			(effects
				(font
					(size 0.7874 0.5842)
					(thickness 0.1524)
				)
			)
		)
		(duplicate_pad_numbers_are_jumpers no)
		(fp_line
			(start 1.143 0.5588)
			(end 1.143 -0.5588)
			(stroke
				(width 0.1)
				(type default)
			)
			(layer "F.SilkS")
		)
		(fp_line
			(start 1.143 -0.5588)
			(end -1.143 -0.5588)
			(stroke
				(width 0.1)
				(type default)
			)
			(layer "F.SilkS")
		)
		(fp_line
			(start -1.143 0.5588)
			(end 1.143 0.5588)
			(stroke
				(width 0.1)
				(type default)
			)
			(layer "F.SilkS")
		)
		(fp_line
			(start -1.143 -0.5588)
			(end -1.143 0.5588)
			(stroke
				(width 0.1)
				(type default)
			)
			(layer "F.SilkS")
		)
		(fp_poly
			(pts
				(xy -1.143 0.5588) (xy 1.143 0.5588) (xy 1.143 -0.5588) (xy -1.143 -0.5588)
			)
			(stroke
				(width 0)
				(type default)
			)
			(fill no)
			(layer "F.CrtYd")
		)
		(fp_line
			(start 0.508 0.3048)
			(end 0.508 -0.3048)
			(stroke
				(width 0.1)
				(type default)
			)
			(layer "F.Fab")
		)
		(fp_line
			(start 0.508 -0.3048)
			(end -0.508 -0.3048)
			(stroke
				(width 0.1)
				(type default)
			)
			(layer "F.Fab")
		)
		(fp_line
			(start -0.508 0.3048)
			(end 0.508 0.3048)
			(stroke
				(width 0.1)
				(type default)
			)
			(layer "F.Fab")
		)
		(fp_line
			(start -0.508 -0.3048)
			(end -0.508 0.3048)
			(stroke
				(width 0.1)
				(type default)
			)
			(layer "F.Fab")
		)
		(pad "1" smd rect
			(at -0.5334 0 180)
			(size 0.7112 0.6096)
			(layers "F.Cu" "F.Mask" "F.Paste")
			(net "MUX1_SEL")
		)
		(pad "2" smd rect
			(at 0.5334 0 180)
			(size 0.7112 0.6096)
			(layers "F.Cu" "F.Mask" "F.Paste")
			(net "FT4232_MUX1_SEL")
		)
		(zone
			(layer "F.Cu")
			(hatch none 0.5)
			(connect_pads
				(clearance 0)
			)
			(min_thickness 0.25)
			(keepout
				(tracks allowed)
				(vias not_allowed)
				(pads allowed)
				(copperpour not_allowed)
				(footprints allowed)
			)
			(placement
				(enabled no)
				(sheetname "")
			)
			(fill
				(thermal_gap 0.5)
				(thermal_bridge_width 0.5)
				(island_removal_mode 0)
			)
			(polygon
				(pts
					(xy 98.1202 -95.758) (xy 97.9678 -95.758) (xy 97.9678 -95.1484) (xy 98.1202 -95.1484)
				)
			)
		)
		(zone
			(layer "F.Cu")
			(hatch none 0.5)
			(connect_pads
				(clearance 0)
			)
			(min_thickness 0.25)
			(keepout
				(tracks not_allowed)
				(vias allowed)
				(pads allowed)
				(copperpour not_allowed)
				(footprints allowed)
			)
			(placement
				(enabled no)
				(sheetname "")
			)
			(fill
				(thermal_gap 0.5)
				(thermal_bridge_width 0.5)
				(island_removal_mode 0)
			)
			(polygon
				(pts
					(xy 98.1202 -95.758) (xy 97.9678 -95.758) (xy 97.9678 -95.1484) (xy 98.1202 -95.1484)
				)
			)
		)
	)
	(footprint ""
		(layer "F.Cu")
		(at 82.169 -66.802)
		(property "Reference" "TP16"
			(at -2.3114 -0.73025 0)
			(unlocked yes)
			(layer "F.SilkS")
			(effects
				(font
					(size 0.635 0.4064)
					(thickness 0.1524)
				)
				(justify left)
			)
		)
		(property "Value" ""
			(at 0 0 0)
			(layer "F.Fab")
			(effects
				(font
					(size 1.27 1.27)
				)
			)
		)
		(property "Device Type" "TP_PIONT-TP010CT020B030_PTH-TPA"
			(at -1.341882 0.996696 0)
			(unlocked yes)
			(layer "F.Fab")
			(hide yes)
			(effects
				(font
					(size 0.7874 0.5842)
					(thickness 0.000001)
				)
				(justify left)
			)
		)
		(duplicate_pad_numbers_are_jumpers no)
		(fp_poly
			(pts
				(arc
					(start 0.889 0)
					(mid -0.889 0)
					(end 0.889 0)
				)
			)
			(stroke
				(width 0)
				(type default)
			)
			(fill no)
			(layer "B.CrtYd")
		)
		(fp_poly
			(pts
				(arc
					(start 0.889 0)
					(mid -0.889 0)
					(end 0.889 0)
				)
			)
			(stroke
				(width 0)
				(type default)
			)
			(fill no)
			(layer "F.CrtYd")
		)
		(pad "1" thru_hole circle
			(at 0 0)
			(size 0.508 0.508)
			(drill 0.254)
			(layers "*.Cu" "*.Mask")
			(remove_unused_layers no)
			(net "R_BNO080_RST_N")
			(clearance 0.1016)
			(padstack
				(mode front_inner_back)
				(layer "Inner"
					(shape circle)
					(size 0.508 0.508)
					(clearance 0.1016)
				)
				(layer "B.Cu"
					(shape circle)
					(size 0.762 0.762)
					(clearance -0.0254)
				)
			)
		)
	)
	(footprint ""
		(layer "F.Cu")
		(at 73.787 -124.46)
		(property "Reference" "SP39"
			(at 0 0 0)
			(layer "F.SilkS")
			(hide yes)
			(effects
				(font
					(size 1.27 1.27)
				)
			)
		)
		(property "Value" ""
			(at 0 0 0)
			(layer "F.Fab")
			(effects
				(font
					(size 1.27 1.27)
				)
			)
		)
		(duplicate_pad_numbers_are_jumpers no)
	)
)
